(kicad_pcb
	(version 20241229)
	(generator "pcbnew")
	(generator_version "9.0")
	(general
		(thickness 1.6)
		(legacy_teardrops no)
	)
	(paper "A4")
	(title_block
		(title "LPDDR4 testbed")
		(date "2024-03-26")
		(rev "1.2.2")
		(comment 9 "footprints 40-46 of 66")
	)
	(layers
		(0 "F.Cu" signal)
		(4 "In1.Cu" power)
		(6 "In2.Cu" power)
		(8 "In3.Cu" signal)
		(10 "In4.Cu" signal)
		(2 "B.Cu" signal)
		(9 "F.Adhes" user "F.Adhesive")
		(11 "B.Adhes" user "B.Adhesive")
		(13 "F.Paste" user)
		(15 "B.Paste" user)
		(5 "F.SilkS" user "F.Silkscreen")
		(7 "B.SilkS" user "B.Silkscreen")
		(1 "F.Mask" user)
		(3 "B.Mask" user)
		(17 "Dwgs.User" user "User.Drawings")
		(19 "Cmts.User" user "User.Comments")
		(21 "Eco1.User" user "User.Eco1")
		(23 "Eco2.User" user "User.Eco2")
		(25 "Edge.Cuts" user)
		(27 "Margin" user)
		(31 "F.CrtYd" user "F.Courtyard")
		(29 "B.CrtYd" user "B.Courtyard")
		(35 "F.Fab" user)
		(33 "B.Fab" user)
	)
	(footprint "antmicro-footprints:LED_0603_1608Metric_G"
		(layer "F.Cu")
		(at 129.441666 72.9 90)
		(descr "LED SMD 0603 Green")
		(tags "LED SMD 0603 Green")
		(property "Reference" "D2"
			(at 1.25 0.32 90)
			(layer "F.SilkS")
			(effects
				(font
					(size 0.7 0.7)
					(thickness 0.15)
				)
				(justify left bottom)
			)
		)
		(property "Value" "LED_G_0603_KP-1608CGCK"
			(at 0 1.6 90)
			(layer "F.Fab")
			(effects
				(font
					(size 0.7 0.7)
					(thickness 0.15)
				)
				(justify left bottom)
			)
		)
		(property "Author" "Antmicro"
			(at 202.341666 -56.541666 0)
			(layer "F.Fab")
			(hide yes)
			(effects
				(font
					(size 1 1)
					(thickness 0.15)
				)
			)
		)
		(property "License" "Apache-2.0"
			(at 202.341666 -56.541666 0)
			(layer "F.Fab")
			(hide yes)
			(effects
				(font
					(size 1 1)
					(thickness 0.15)
				)
			)
		)
		(property "MPN" "KP-1608CGCK"
			(at 202.341666 -56.541666 0)
			(layer "F.Fab")
			(hide yes)
			(effects
				(font
					(size 1 1)
					(thickness 0.15)
				)
			)
		)
		(property "Manufacturer" "Kingbright"
			(at 202.341666 -56.541666 0)
			(layer "F.Fab")
			(hide yes)
			(effects
				(font
					(size 1 1)
					(thickness 0.15)
				)
			)
		)
		(sheetname "EEPROM")
		(sheetfile "EEPROM.kicad_sch")
		(attr smd)
		(fp_line
			(start -0.27 -0.35)
			(end 0.27 -0.35)
			(stroke
				(width 0.15)
				(type solid)
			)
			(layer "F.SilkS")
		)
		(fp_line
			(start 0.093672 -0.200008)
			(end 0.093672 0.199992)
			(stroke
				(width 0.1)
				(type solid)
			)
			(layer "F.SilkS")
		)
		(fp_line
			(start -0.106328 -0.200008)
			(end 0.093672 -8e-06)
			(stroke
				(width 0.1)
				(type solid)
			)
			(layer "F.SilkS")
		)
		(fp_line
			(start -0.106328 -0.200008)
			(end -0.106328 0.199992)
			(stroke
				(width 0.1)
				(type solid)
			)
			(layer "F.SilkS")
		)
		(fp_line
			(start 0.093672 -8e-06)
			(end 0.293672 -8e-06)
			(stroke
				(width 0.1)
				(type solid)
			)
			(layer "F.SilkS")
		)
		(fp_line
			(start 0.093672 -8e-06)
			(end -0.106328 0.199992)
			(stroke
				(width 0.1)
				(type solid)
			)
			(layer "F.SilkS")
		)
		(fp_line
			(start -0.106328 -8e-06)
			(end -0.29 0)
			(stroke
				(width 0.1)
				(type solid)
			)
			(layer "F.SilkS")
		)
		(fp_line
			(start 1.25 0.32)
			(end 1.25 -0.32)
			(stroke
				(width 0.15)
				(type solid)
			)
			(layer "F.SilkS")
		)
		(fp_line
			(start -0.27 0.351)
			(end 0.27 0.351)
			(stroke
				(width 0.15)
				(type solid)
			)
			(layer "F.SilkS")
		)
		(fp_rect
			(start 1.26 0.65)
			(end -1.26 -0.65)
			(stroke
				(width 0.05)
				(type solid)
			)
			(fill no)
			(layer "F.CrtYd")
		)
		(fp_line
			(start 0.199 -0.2)
			(end 0.199 -0.1)
			(stroke
				(width 0.15)
				(type solid)
			)
			(layer "F.Fab")
		)
		(fp_line
			(start -0.201 -0.2)
			(end -0.201 0)
			(stroke
				(width 0.15)
				(type solid)
			)
			(layer "F.Fab")
		)
		(fp_line
			(start 0.199 0)
			(end 0.597 0)
			(stroke
				(width 0.15)
				(type solid)
			)
			(layer "F.Fab")
		)
		(fp_line
			(start 0.101 0)
			(end -0.201 -0.2)
			(stroke
				(width 0.15)
				(type solid)
			)
			(layer "F.Fab")
		)
		(fp_line
			(start -0.201 0)
			(end -0.201 0.202)
			(stroke
				(width 0.15)
				(type solid)
			)
			(layer "F.Fab")
		)
		(fp_line
			(start -0.599 0)
			(end -0.201 0)
			(stroke
				(width 0.15)
				(type solid)
			)
			(layer "F.Fab")
		)
		(fp_line
			(start 0.199 0.202)
			(end 0.199 -0.1)
			(stroke
				(width 0.15)
				(type solid)
			)
			(layer "F.Fab")
		)
		(fp_line
			(start -0.201 0.202)
			(end 0.101 0)
			(stroke
				(width 0.15)
				(type solid)
			)
			(layer "F.Fab")
		)
		(fp_rect
			(start -0.848 -0.4)
			(end 0.85 0.402)
			(stroke
				(width 0.15)
				(type solid)
			)
			(fill no)
			(layer "F.Fab")
		)
		(pad "1" smd rect
			(at -0.75 0 270)
			(size 0.8 0.8)
			(layers "F.Cu" "F.Mask" "F.Paste")
			(net 256 "Net-(D2-Pad1)")
			(pinfunction "1")
			(pintype "passive")
		)
		(pad "2" smd rect
			(at 0.75 0 270)
			(size 0.8 0.8)
			(layers "F.Cu" "F.Mask" "F.Paste")
			(net 36 "GND")
			(pinfunction "2")
			(pintype "passive")
		)
	)
	(footprint "antmicro-footprints:R_0402_1005Metric"
		(layer "F.Cu")
		(at 127.625 75.95 90)
		(descr "Resistor SMD 0402")
		(tags "resistor SMD 0402")
		(property "Reference" "R9"
			(at -1 -0.5 90)
			(layer "F.SilkS")
			(effects
				(font
					(size 0.7 0.7)
					(thickness 0.15)
				)
				(justify left bottom)
			)
		)
		(property "Value" "R_220R_0402"
			(at 0 1.4 90)
			(layer "F.Fab")
			(effects
				(font
					(size 0.7 0.7)
					(thickness 0.15)
				)
				(justify left bottom)
			)
		)
		(property "Description" "220R resistor in 0402 package with 1% tolerance"
			(at 0 0 90)
			(layer "F.Fab")
			(hide yes)
			(effects
				(font
					(size 1.27 1.27)
					(thickness 0.15)
				)
			)
		)
		(property "Author" "Antmicro"
			(at 203.575 -51.675 0)
			(layer "F.Fab")
			(hide yes)
			(effects
				(font
					(size 1 1)
					(thickness 0.15)
				)
			)
		)
		(property "License" "Apache-2.0"
			(at 203.575 -51.675 0)
			(layer "F.Fab")
			(hide yes)
			(effects
				(font
					(size 1 1)
					(thickness 0.15)
				)
			)
		)
		(property "MPN" "ERJ2GEJ221X"
			(at 203.575 -51.675 0)
			(layer "F.Fab")
			(hide yes)
			(effects
				(font
					(size 1 1)
					(thickness 0.15)
				)
			)
		)
		(property "Manufacturer" "Panasonic"
			(at 203.575 -51.675 0)
			(layer "F.Fab")
			(hide yes)
			(effects
				(font
					(size 1 1)
					(thickness 0.15)
				)
			)
		)
		(property "Tolerance" "1%"
			(at 203.575 -51.675 0)
			(layer "F.Fab")
			(hide yes)
			(effects
				(font
					(size 1 1)
					(thickness 0.15)
				)
			)
		)
		(property "Val" "220R"
			(at 203.575 -51.675 0)
			(layer "F.Fab")
			(hide yes)
			(effects
				(font
					(size 1 1)
					(thickness 0.15)
				)
			)
		)
		(sheetname "EEPROM")
		(sheetfile "EEPROM.kicad_sch")
		(attr smd)
		(fp_rect
			(start -0.93 -0.47)
			(end 0.93 0.47)
			(stroke
				(width 0.05)
				(type solid)
			)
			(fill no)
			(layer "F.CrtYd")
		)
		(fp_rect
			(start -0.5 -0.25)
			(end 0.5 0.25)
			(stroke
				(width 0.15)
				(type solid)
			)
			(fill no)
			(layer "F.Fab")
		)
		(pad "1" smd roundrect
			(at -0.485 0 90)
			(size 0.59 0.64)
			(layers "F.Cu" "F.Mask" "F.Paste")
			(roundrect_rratio 0.25)
			(net 1 "Net-(IC1-P0)")
			(pintype "passive")
		)
		(pad "2" smd roundrect
			(at 0.485 0 90)
			(size 0.59 0.64)
			(layers "F.Cu" "F.Mask" "F.Paste")
			(roundrect_rratio 0.25)
			(net 255 "Net-(D1-Pad1)")
			(pintype "passive")
		)
	)
	(footprint "antmicro-footprints:R_0402_1005Metric"
		(layer "F.Cu")
		(at 129.441666 75.95 90)
		(descr "Resistor SMD 0402")
		(tags "resistor SMD 0402")
		(property "Reference" "R10"
			(at -1 -0.5 90)
			(layer "F.SilkS")
			(effects
				(font
					(size 0.7 0.7)
					(thickness 0.15)
				)
				(justify left bottom)
			)
		)
		(property "Value" "R_220R_0402"
			(at 0 1.4 90)
			(layer "F.Fab")
			(effects
				(font
					(size 0.7 0.7)
					(thickness 0.15)
				)
				(justify left bottom)
			)
		)
		(property "Description" "220R resistor in 0402 package with 1% tolerance"
			(at 0 0 90)
			(layer "F.Fab")
			(hide yes)
			(effects
				(font
					(size 1.27 1.27)
					(thickness 0.15)
				)
			)
		)
		(property "Author" "Antmicro"
			(at 205.391666 -53.491666 0)
			(layer "F.Fab")
			(hide yes)
			(effects
				(font
					(size 1 1)
					(thickness 0.15)
				)
			)
		)
		(property "License" "Apache-2.0"
			(at 205.391666 -53.491666 0)
			(layer "F.Fab")
			(hide yes)
			(effects
				(font
					(size 1 1)
					(thickness 0.15)
				)
			)
		)
		(property "MPN" "ERJ2GEJ221X"
			(at 205.391666 -53.491666 0)
			(layer "F.Fab")
			(hide yes)
			(effects
				(font
					(size 1 1)
					(thickness 0.15)
				)
			)
		)
		(property "Manufacturer" "Panasonic"
			(at 205.391666 -53.491666 0)
			(layer "F.Fab")
			(hide yes)
			(effects
				(font
					(size 1 1)
					(thickness 0.15)
				)
			)
		)
		(property "Tolerance" "1%"
			(at 205.391666 -53.491666 0)
			(layer "F.Fab")
			(hide yes)
			(effects
				(font
					(size 1 1)
					(thickness 0.15)
				)
			)
		)
		(property "Val" "220R"
			(at 205.391666 -53.491666 0)
			(layer "F.Fab")
			(hide yes)
			(effects
				(font
					(size 1 1)
					(thickness 0.15)
				)
			)
		)
		(sheetname "EEPROM")
		(sheetfile "EEPROM.kicad_sch")
		(attr smd)
		(fp_rect
			(start -0.93 -0.47)
			(end 0.93 0.47)
			(stroke
				(width 0.05)
				(type solid)
			)
			(fill no)
			(layer "F.CrtYd")
		)
		(fp_rect
			(start -0.5 -0.25)
			(end 0.5 0.25)
			(stroke
				(width 0.15)
				(type solid)
			)
			(fill no)
			(layer "F.Fab")
		)
		(pad "1" smd roundrect
			(at -0.485 0 90)
			(size 0.59 0.64)
			(layers "F.Cu" "F.Mask" "F.Paste")
			(roundrect_rratio 0.25)
			(net 2 "Net-(IC1-P1)")
			(pintype "passive")
		)
		(pad "2" smd roundrect
			(at 0.485 0 90)
			(size 0.59 0.64)
			(layers "F.Cu" "F.Mask" "F.Paste")
			(roundrect_rratio 0.25)
			(net 256 "Net-(D2-Pad1)")
			(pintype "passive")
		)
	)
	(footprint "antmicro-footprints:R_0402_1005Metric"
		(layer "F.Cu")
		(at 131.258332 75.95 90)
		(descr "Resistor SMD 0402")
		(tags "resistor SMD 0402")
		(property "Reference" "R11"
			(at -1 -0.5 90)
			(layer "F.SilkS")
			(effects
				(font
					(size 0.7 0.7)
					(thickness 0.15)
				)
				(justify left bottom)
			)
		)
		(property "Value" "R_220R_0402"
			(at 0 1.4 90)
			(layer "F.Fab")
			(effects
				(font
					(size 0.7 0.7)
					(thickness 0.15)
				)
				(justify left bottom)
			)
		)
		(property "Description" "220R resistor in 0402 package with 1% tolerance"
			(at 0 0 90)
			(layer "F.Fab")
			(hide yes)
			(effects
				(font
					(size 1.27 1.27)
					(thickness 0.15)
				)
			)
		)
		(property "Author" "Antmicro"
			(at 207.208332 -55.308332 0)
			(layer "F.Fab")
			(hide yes)
			(effects
				(font
					(size 1 1)
					(thickness 0.15)
				)
			)
		)
		(property "License" "Apache-2.0"
			(at 207.208332 -55.308332 0)
			(layer "F.Fab")
			(hide yes)
			(effects
				(font
					(size 1 1)
					(thickness 0.15)
				)
			)
		)
		(property "MPN" "ERJ2GEJ221X"
			(at 207.208332 -55.308332 0)
			(layer "F.Fab")
			(hide yes)
			(effects
				(font
					(size 1 1)
					(thickness 0.15)
				)
			)
		)
		(property "Manufacturer" "Panasonic"
			(at 207.208332 -55.308332 0)
			(layer "F.Fab")
			(hide yes)
			(effects
				(font
					(size 1 1)
					(thickness 0.15)
				)
			)
		)
		(property "Tolerance" "1%"
			(at 207.208332 -55.308332 0)
			(layer "F.Fab")
			(hide yes)
			(effects
				(font
					(size 1 1)
					(thickness 0.15)
				)
			)
		)
		(property "Val" "220R"
			(at 207.208332 -55.308332 0)
			(layer "F.Fab")
			(hide yes)
			(effects
				(font
					(size 1 1)
					(thickness 0.15)
				)
			)
		)
		(sheetname "EEPROM")
		(sheetfile "EEPROM.kicad_sch")
		(attr smd)
		(fp_rect
			(start -0.93 -0.47)
			(end 0.93 0.47)
			(stroke
				(width 0.05)
				(type solid)
			)
			(fill no)
			(layer "F.CrtYd")
		)
		(fp_rect
			(start -0.5 -0.25)
			(end 0.5 0.25)
			(stroke
				(width 0.15)
				(type solid)
			)
			(fill no)
			(layer "F.Fab")
		)
		(pad "1" smd roundrect
			(at -0.485 0 90)
			(size 0.59 0.64)
			(layers "F.Cu" "F.Mask" "F.Paste")
			(roundrect_rratio 0.25)
			(net 3 "Net-(IC1-P2)")
			(pintype "passive")
		)
		(pad "2" smd roundrect
			(at 0.485 0 90)
			(size 0.59 0.64)
			(layers "F.Cu" "F.Mask" "F.Paste")
			(roundrect_rratio 0.25)
			(net 257 "Net-(D3-Pad1)")
			(pintype "passive")
		)
	)
	(footprint "antmicro-footprints:TP_SMD_0.75mm"
		(layer "F.Cu")
		(at 127.975 88.55)
		(property "Reference" "TP1"
			(at -2.4 0 0)
			(layer "F.SilkS")
			(effects
				(font
					(size 0.7 0.7)
					(thickness 0.15)
				)
				(justify left bottom)
			)
		)
		(property "Value" "TP_0.75mm_SMD"
			(at 0 1.2 0)
			(layer "F.Fab")
			(effects
				(font
					(size 0.7 0.7)
					(thickness 0.15)
				)
				(justify left bottom)
			)
		)
		(property "Description" "Test Point 0.75mm"
			(at 0 0 0)
			(layer "F.Fab")
			(hide yes)
			(effects
				(font
					(size 1.27 1.27)
					(thickness 0.15)
				)
			)
		)
		(property "Author" "Antmicro"
			(at 0 0 0)
			(layer "F.Fab")
			(hide yes)
			(effects
				(font
					(size 1 1)
					(thickness 0.15)
				)
			)
		)
		(property "License" "Apache-2.0"
			(at 0 0 0)
			(layer "F.Fab")
			(hide yes)
			(effects
				(font
					(size 1 1)
					(thickness 0.15)
				)
			)
		)
		(property "MPN" ""
			(at 0 0 0)
			(layer "F.Fab")
			(hide yes)
			(effects
				(font
					(size 1 1)
					(thickness 0.15)
				)
			)
		)
		(property "Manufacturer" ""
			(at 0 0 0)
			(layer "F.Fab")
			(hide yes)
			(effects
				(font
					(size 1 1)
					(thickness 0.15)
				)
			)
		)
		(sheetname "EEPROM")
		(sheetfile "EEPROM.kicad_sch")
		(attr exclude_from_pos_files)
		(pad "1" smd circle
			(at 0 0)
			(size 0.75 0.75)
			(layers "F.Cu" "F.Mask")
			(net 152 "Net-(IC1-P4)")
			(pinfunction "1")
			(pintype "passive")
		)
	)
	(footprint "antmicro-footprints:C_0402_1005Metric"
		(layer "F.Cu")
		(at 132.175 91.615 -90)
		(descr "Capacitor SMD 0402")
		(tags "capacitor SMD 0402")
		(property "Reference" "C39"
			(at -1.065 -1.4 90)
			(layer "F.SilkS")
			(effects
				(font
					(size 0.7 0.7)
					(thickness 0.15)
				)
				(justify right bottom)
			)
		)
		(property "Value" "C_100n_0402"
			(at 0 1.4 90)
			(layer "F.Fab")
			(effects
				(font
					(size 0.7 0.7)
					(thickness 0.15)
				)
				(justify right bottom)
			)
		)
		(property "Description" " "
			(at 0 0 270)
			(layer "F.Fab")
			(hide yes)
			(effects
				(font
					(size 1.27 1.27)
					(thickness 0.15)
				)
			)
		)
		(property "Author" "Antmicro"
			(at 40.56 223.79 0)
			(layer "F.Fab")
			(hide yes)
			(effects
				(font
					(size 1 1)
					(thickness 0.15)
				)
			)
		)
		(property "Dielectric" "X5R"
			(at 40.56 223.79 0)
			(layer "F.Fab")
			(hide yes)
			(effects
				(font
					(size 1 1)
					(thickness 0.15)
				)
			)
		)
		(property "License" "Apache-2.0"
			(at 40.56 223.79 0)
			(layer "F.Fab")
			(hide yes)
			(effects
				(font
					(size 1 1)
					(thickness 0.15)
				)
			)
		)
		(property "MPN" "0402X104K6R3CT"
			(at 40.56 223.79 0)
			(layer "F.Fab")
			(hide yes)
			(effects
				(font
					(size 1 1)
					(thickness 0.15)
				)
			)
		)
		(property "Manufacturer" "Walsin"
			(at 40.56 223.79 0)
			(layer "F.Fab")
			(hide yes)
			(effects
				(font
					(size 1 1)
					(thickness 0.15)
				)
			)
		)
		(property "Val" "100n"
			(at 40.56 223.79 0)
			(layer "F.Fab")
			(hide yes)
			(effects
				(font
					(size 1 1)
					(thickness 0.15)
				)
			)
		)
		(property "Voltage" "50V"
			(at 40.56 223.79 0)
			(layer "F.Fab")
			(hide yes)
			(effects
				(font
					(size 1 1)
					(thickness 0.15)
				)
			)
		)
		(sheetname "EEPROM")
		(sheetfile "EEPROM.kicad_sch")
		(attr smd)
		(fp_rect
			(start -0.94 -0.47)
			(end 0.94 0.47)
			(stroke
				(width 0.05)
				(type solid)
			)
			(fill no)
			(layer "F.CrtYd")
		)
		(fp_rect
			(start -0.499 -0.249)
			(end 0.499 0.249)
			(stroke
				(width 0.15)
				(type solid)
			)
			(fill no)
			(layer "F.Fab")
		)
		(pad "1" smd roundrect
			(at -0.484 0 270)
			(size 0.59 0.64)
			(layers "F.Cu" "F.Mask" "F.Paste")
			(roundrect_rratio 0.25)
			(net 36 "GND")
			(pintype "passive")
		)
		(pad "2" smd roundrect
			(at 0.484 0 270)
			(size 0.59 0.64)
			(layers "F.Cu" "F.Mask" "F.Paste")
			(roundrect_rratio 0.25)
			(net 187 "VDD1")
			(pintype "passive")
		)
	)
	(footprint "antmicro-footprints:R_0402_1005Metric"
		(layer "F.Cu")
		(at 126.56 92.585 90)
		(descr "Resistor SMD 0402")
		(tags "resistor SMD 0402")
		(property "Reference" "R13"
			(at -1.165 -0.585 90)
			(layer "F.SilkS")
			(effects
				(font
					(size 0.7 0.7)
					(thickness 0.15)
				)
				(justify left bottom)
			)
		)
		(property "Value" "R_10k_0402"
			(at 0 1.4 90)
			(layer "F.Fab")
			(effects
				(font
					(size 0.7 0.7)
					(thickness 0.15)
				)
				(justify left bottom)
			)
		)
		(property "Description" "10k resistor in 0402 package with 1% tolerance"
			(at 0 0 90)
			(layer "F.Fab")
			(hide yes)
			(effects
				(font
					(size 1.27 1.27)
					(thickness 0.15)
				)
			)
		)
		(property "Author" "Antmicro"
			(at 219.145 -33.975 0)
			(layer "F.Fab")
			(hide yes)
			(effects
				(font
					(size 1 1)
					(thickness 0.15)
				)
			)
		)
		(property "License" "Apache-2.0"
			(at 219.145 -33.975 0)
			(layer "F.Fab")
			(hide yes)
			(effects
				(font
					(size 1 1)
					(thickness 0.15)
				)
			)
		)
		(property "MPN" "CRCW040210K0FKEDHP"
			(at 219.145 -33.975 0)
			(layer "F.Fab")
			(hide yes)
			(effects
				(font
					(size 1 1)
					(thickness 0.15)
				)
			)
		)
		(property "Manufacturer" "VISHAY"
			(at 219.145 -33.975 0)
			(layer "F.Fab")
			(hide yes)
			(effects
				(font
					(size 1 1)
					(thickness 0.15)
				)
			)
		)
		(property "Tolerance" "1%"
			(at 219.145 -33.975 0)
			(layer "F.Fab")
			(hide yes)
			(effects
				(font
					(size 1 1)
					(thickness 0.15)
				)
			)
		)
		(property "Val" "10k"
			(at 219.145 -33.975 0)
			(layer "F.Fab")
			(hide yes)
			(effects
				(font
					(size 1 1)
					(thickness 0.15)
				)
			)
		)
		(sheetname "EEPROM")
		(sheetfile "EEPROM.kicad_sch")
		(attr smd)
		(fp_rect
			(start -0.93 -0.47)
			(end 0.93 0.47)
			(stroke
				(width 0.05)
				(type solid)
			)
			(fill no)
			(layer "F.CrtYd")
		)
		(fp_rect
			(start -0.5 -0.25)
			(end 0.5 0.25)
			(stroke
				(width 0.15)
				(type solid)
			)
			(fill no)
			(layer "F.Fab")
		)
		(pad "1" smd roundrect
			(at -0.485 0 90)
			(size 0.59 0.64)
			(layers "F.Cu" "F.Mask" "F.Paste")
			(roundrect_rratio 0.25)
			(net 187 "VDD1")
			(pintype "passive")
		)
		(pad "2" smd roundrect
			(at 0.485 0 90)
			(size 0.59 0.64)
			(layers "F.Cu" "F.Mask" "F.Paste")
			(roundrect_rratio 0.25)
			(net 246 "SDA")
			(pintype "passive")
		)
	)
)
